FILE_TYPE = CONNECTIVITY;
{Allegro Design Entry HDL 17.2-2016 S081 (4005846) 1/11/2022}
"PAGE_NUMBER" = 170;
0"NC";
1"GND\g";
2"GND\g";
3"GND\g";
4"GND\g";
5"GND\g";
6"GND\g";
7"GND\g";
8"GND\g";
9"GND\g";
10"GND\g";
11"SW_PVDDCR_CPU0_P0_BOOT4_RC";
12"GND\g";
13"SW_PVDDCR_CPU0_P0_SW4";
14"SW_PVDDCR_CPU0_P0_PH4";
15"SW_PVDDCR_CPU0_P0_PH3";
16"SW_PVDDCR_CPU0_P0_BOOT3";
17"GND\g";
18"SW_PVDDCR_CPU0_P0_SW3";
19"PVDDCR_CPU0_P0_VCCS";
20"PVDDCR_CPU0_P0_PWM4";
21"PVDDCR_CPU0_P0_LSET4";
22"NC_PVDDCR_CPU0_P0_DNC4";
23"PVDDCR_CPU0_P0_VCC4";
24"PVDDCR_CPU0_P0_TEMP0";
25"PVDDCR_CPU0_P0_IMON4";
26"PVDDCR_CPU0_P0_PVCC\g";
27"GND\g";
28"NC_PVDDCR_CPU0_P0_GL2_4";
29"NC_PVDDCR_CPU0_P0_GL1_4";
30"SW_PVDDCR_CPU0_P0_BOOT4";
31"PVDDCR_CPU0_P0_VOS4";
32"SW_PVDDCR_CPU0_P0_SW4_RC";
33"SW_P12V_STBY_PVDDCR_CPU0_P0_FLT\g";
34"PVDDCR_CPU0_P0_VOS3";
35"PVDDCR_CPU0_P0_VCC3";
36"PVDDCR_CPU0_P0_VCCS";
37"NC_PVDDCR_CPU0_P0_DNC3";
38"PVDDCR_CPU0_P0_LSET3";
39"PVDDCR_CPU0_P0_IMON3";
40"PVDDCR_CPU0_P0_TEMP0";
41"PVDDCR_CPU0_P0_PWM3";
42"PVDDCR_CPU0_P0_PVCC\g";
43"GND\g";
44"SW_P12V_STBY_PVDDCR_CPU0_P0_FLT\g";
45"NC_PVDDCR_CPU0_P0_GL1_3";
46"NC_PVDDCR_CPU0_P0_GL2_3";
47"SW_PVDDCR_CPU0_P0_SW3_RC";
48"IND_CPU0_P0_CPL3";
49"PVDDCR_CPU0_P0\g";
50"GND\g";
51"GND\g";
52"PVDDCR_CPU0_P0\g";
53"IND_CPU0_P0_CPL2";
54"SW_PVDDCR_CPU0_P0_BOOT3_RC";
55"IND_CPU0_P0_CPL3";
56"GND\g";
%"UNIVERSAL_GND"
"1","(-7775,4350)","0","pure_quanta_power","I1";
;
CDS_LIB"pure_quanta_power"
HDL_POWER"GND";
"A"1;
%"UNIVERSAL_GND"
"1","(-7375,1125)","0","pure_quanta_power","I102";
;
CDS_LIB"pure_quanta_power"
HDL_POWER"GND";
"A"2;
%"Q_CAP"
"1","(-7700,1325)","0","pure_quanta","I105";
;
LOCATION"PC545_4"
$SEC"1"
CDS_SEC"1"
MATERIAL"X7R"
TOLERANCE"10%"
VALUE"0.1UF"
PART_NUMBER"CH4104K1B00"
VOLTAGE"25V"
PACK_TYPE"0402"
CDS_LIB"pure_quanta";
"B"
$PN"2"3;
"A"
$PN"1"19;
%"UNIVERSAL_GND"
"1","(-7700,1050)","0","pure_quanta_power","I106";
;
CDS_LIB"pure_quanta_power"
HDL_POWER"GND";
"A"3;
%"Q_CAP"
"1","(-5325,5800)","0","pure_quanta","I107";
;
LOCATION"PC550_3"
$SEC"1"
CDS_SEC"1"
MATERIAL"X7R"
TOLERANCE"10%"
VALUE"0.1UF"
PART_NUMBER"CH4104K1B00"
VOLTAGE"25V"
PACK_TYPE"0402"
CDS_LIB"pure_quanta";
"B"
$PN"2"17;
"A"
$PN"1"44;
%"Q_CAP"
"1","(-5200,2500)","0","pure_quanta","I108";
;
LOCATION"PC551_4"
$SEC"1"
CDS_SEC"1"
MATERIAL"X7R"
TOLERANCE"10%"
VALUE"0.1UF"
PART_NUMBER"CH4104K1B00"
VOLTAGE"25V"
PACK_TYPE"0402"
CDS_LIB"pure_quanta";
"B"
$PN"2"12;
"A"
$PN"1"33;
%"Q_CAP"
"1","(-7450,5250)","0","pure_quanta","I109";
;
LOCATION"PC546"
$SEC"1"
CDS_SEC"1"
MATERIAL"X6S"
TOLERANCE"10%"
VALUE"2.2UF"
PART_NUMBER"CH5222KEB01"
VOLTAGE"10V"
PACK_TYPE"C0402"
CDS_LIB"pure_quanta";
"B"
$PN"2"4;
"A"
$PN"1"35;
%"UNIVERSAL_GND"
"1","(-7450,5050)","0","pure_quanta_power","I110";
;
CDS_LIB"pure_quanta_power"
HDL_POWER"GND";
"A"4;
%"UNIVERSAL_GND"
"1","(-7100,5500)","0","pure_quanta_power","I111";
;
CDS_LIB"pure_quanta_power"
HDL_POWER"GND";
"A"5;
%"Q_RES"
"2","(-7450,5750)","0","pure_quanta","I112";
;
LOCATION"PR344"
$SEC"1"
CDS_SEC"1"
WATTAGE"1/16W"
MATERIAL"CHIP"
TOLERANCE"1%"
VALUE"2.2"
PART_NUMBER"CS-2202FB00"
PACK_TYPE"0402LF"
CDS_LIB"pure_quanta";
"A"
$PN"1"42;
"B"
$PN"2"35;
%"Q_CAP"
"1","(-7100,5750)","0","pure_quanta","I113";
;
LOCATION"PC548_C0P0_3"
$SEC"1"
CDS_SEC"1"
MATERIAL"X6S"
TOLERANCE"10%"
VALUE"2.2UF"
PART_NUMBER"CH5222KEB01"
VOLTAGE"10V"
PACK_TYPE"C0402"
CDS_LIB"pure_quanta";
"B"
$PN"2"5;
"A"
$PN"1"42;
%"Q_CAP"
"1","(-7350,1950)","0","pure_quanta","I115";
;
LOCATION"PC547"
$SEC"1"
CDS_SEC"1"
MATERIAL"X6S"
TOLERANCE"10%"
VALUE"2.2UF"
PART_NUMBER"CH5222KEB01"
VOLTAGE"10V"
PACK_TYPE"C0402"
CDS_LIB"pure_quanta";
"B"
$PN"2"6;
"A"
$PN"1"23;
%"UNIVERSAL_GND"
"1","(-7350,1750)","0","pure_quanta_power","I116";
;
CDS_LIB"pure_quanta_power"
HDL_POWER"GND";
"A"6;
%"UNIVERSAL_GND"
"1","(-7000,2250)","0","pure_quanta_power","I117";
;
CDS_LIB"pure_quanta_power"
HDL_POWER"GND";
"A"7;
%"Q_RES"
"2","(-7350,2500)","0","pure_quanta","I118";
;
LOCATION"PR345"
$SEC"1"
CDS_SEC"1"
WATTAGE"1/16W"
MATERIAL"CHIP"
TOLERANCE"1%"
VALUE"2.2"
PART_NUMBER"CS-2202FB00"
PACK_TYPE"0402LF"
CDS_LIB"pure_quanta";
"A"
$PN"1"26;
"B"
$PN"2"23;
%"Q_CAP"
"1","(-7000,2525)","0","pure_quanta","I119";
;
LOCATION"PC549_C0P0_4"
$SEC"1"
CDS_SEC"1"
MATERIAL"X6S"
TOLERANCE"10%"
VALUE"2.2UF"
PART_NUMBER"CH5222KEB01"
VOLTAGE"10V"
PACK_TYPE"C0402"
CDS_LIB"pure_quanta";
"B"
$PN"2"7;
"A"
$PN"1"26;
%"ISL99390FRZTR5935"
"1","(-5950,4900)","0","pure_quanta","I121";
;
LOCATION"PU46"
$SEC"1"
CDS_SEC"1"
PART_TYPE"SMLF"
MATERIAL"IC"
VALUE"ISL99390FRZ-TR5935"
PART_NUMBER"AL099390004"
CDS_LIB"pure_quanta"
NEEDS_NO_SIZE"TRUE"
CDS_LMAN_SYM_OUTLINE"-300,700,250,-650";
"PGND2"
$PN"7_9-20_24"43;
"GL2"
$PN"41"46;
"GL1"
$PN"6"45;
"DNC"
$PN"31"37;
"EN"
$PN"35"35;
"PGND3"
$PN"40"43;
"VOS"
$PN"1"34;
"VIN2"
$PN"30"44;
"PGND1"
$PN"5"43;
"SW"
$PN"10_19"18;
"LSET"
$PN"37"38;
"IOUT"
$PN"38"39;
"TOUT_FLT"
$PN"36"40;
"PVCC"
$PN"4"42;
"PHASE"
$PN"32"15;
"VIN1"
$PN"25_29"44;
"BOOT"
$PN"33"16;
"AGND"
$PN"2"43;
"VCC"
$PN"3"35;
"REFIN"
$PN"39"36;
"PWM"
$PN"34"41;
%"ISL99390FRZTR5935"
"1","(-5875,1600)","0","pure_quanta","I122";
;
LOCATION"PU47"
$SEC"1"
CDS_SEC"1"
PART_TYPE"SMLF"
MATERIAL"IC"
VALUE"ISL99390FRZ-TR5935"
PART_NUMBER"AL099390004"
CDS_LIB"pure_quanta"
NEEDS_NO_SIZE"TRUE"
CDS_LMAN_SYM_OUTLINE"-300,700,250,-650";
"PGND2"
$PN"7_9-20_24"27;
"GL2"
$PN"41"28;
"GL1"
$PN"6"29;
"DNC"
$PN"31"22;
"EN"
$PN"35"23;
"PGND3"
$PN"40"27;
"VOS"
$PN"1"31;
"VIN2"
$PN"30"33;
"PGND1"
$PN"5"27;
"SW"
$PN"10_19"13;
"LSET"
$PN"37"21;
"IOUT"
$PN"38"25;
"TOUT_FLT"
$PN"36"24;
"PVCC"
$PN"4"26;
"PHASE"
$PN"32"14;
"VIN1"
$PN"25_29"33;
"BOOT"
$PN"33"30;
"AGND"
$PN"2"27;
"VCC"
$PN"3"23;
"REFIN"
$PN"39"19;
"PWM"
$PN"34"20;
%"Q_CAP"
"1","(-4475,4725)","0","pure_quanta","I123";
;
LOCATION"PC180"
$SEC"1"
CDS_SEC"1"
MATERIAL"EMPTY"
TOLERANCE"10%"
VALUE"560PF"
PART_NUMBER"CH1566K1B09"
VOLTAGE"50V"
PACK_TYPE"C0402"
CDS_LIB"pure_quanta";
"B"
$PN"2"47;
"A"
$PN"1"18;
%"Q_RES"
"2","(-4475,4250)","0","pure_quanta","I124";
;
LOCATION"PR498"
$SEC"1"
CDS_SEC"1"
WATTAGE"1/8W"
MATERIAL"EMPTY"
TOLERANCE"1%"
VALUE"1.5"
PART_NUMBER"CS-1504FB00"
PACK_TYPE"0402LF"
CDS_LIB"pure_quanta";
"A"
$PN"1"47;
"B"
$PN"2"8;
%"UNIVERSAL_GND"
"1","(-4475,4025)","0","pure_quanta_power","I125";
;
CDS_LIB"pure_quanta_power"
HDL_POWER"GND";
"A"8;
%"Q_CAP"
"1","(-4400,1425)","0","pure_quanta","I126";
;
LOCATION"PC181"
$SEC"1"
CDS_SEC"1"
MATERIAL"EMPTY"
TOLERANCE"10%"
VALUE"560PF"
PART_NUMBER"CH1566K1B09"
VOLTAGE"50V"
PACK_TYPE"C0402"
CDS_LIB"pure_quanta";
"B"
$PN"2"32;
"A"
$PN"1"13;
%"Q_RES"
"2","(-4400,975)","0","pure_quanta","I127";
;
LOCATION"PR499"
$SEC"1"
CDS_SEC"1"
WATTAGE"1/8W"
MATERIAL"EMPTY"
TOLERANCE"1%"
VALUE"1.5"
PART_NUMBER"CS-1504FB00"
PACK_TYPE"0402LF"
CDS_LIB"pure_quanta";
"A"
$PN"1"32;
"B"
$PN"2"9;
%"UNIVERSAL_GND"
"1","(-4400,750)","0","pure_quanta_power","I128";
;
CDS_LIB"pure_quanta_power"
HDL_POWER"GND";
"A"9;
%"UNIVERSAL_GND"
"1","(-1975,1150)","0","pure_quanta_power","I129";
;
CDS_LIB"pure_quanta_power"
HDL_POWER"GND";
"A"50;
%"VCC_CORE"
"1","(-7450,6200)","0","pure_quanta_power","I130";
;
HDL_POWER"PVDDCR_CPU0_P0_PVCC"
CDS_LIB"pure_quanta_power";
"A"42;
%"VCC_CORE"
"1","(-7350,2900)","0","pure_quanta_power","I131";
;
HDL_POWER"PVDDCR_CPU0_P0_PVCC"
CDS_LIB"pure_quanta_power";
"A"26;
%"UNIVERSAL_GND"
"1","(-5400,4125)","0","pure_quanta_power","I15";
;
CDS_LIB"pure_quanta_power"
HDL_POWER"GND";
"A"43;
%"Q_RES"
"1","(-4150,3950)","0","pure_quanta","I16";
;
LOCATION"PR350"
$SEC"1"
CDS_SEC"1"
WATTAGE"1/16W"
MATERIAL"CHIP"
TOLERANCE"5%"
VALUE"0"
PART_NUMBER"CS00002JB38"
PACK_TYPE"0402LF"
CDS_LIB"pure_quanta";
"B"
$PN"2"52;
"A"
$PN"1"34;
%"Q_RES"
"1","(-4550,5250)","0","pure_quanta","I18";
;
LOCATION"PR348"
$SEC"1"
CDS_SEC"1"
PACK_TYPE"0402LF"
TOLERANCE"1%"
MATERIAL"CHIP"
WATTAGE"1/16W"
VALUE"4.7"
PART_NUMBER"CS-4702FB19"
CDS_LIB"pure_quanta";
"B"
$PN"2"54;
"A"
$PN"1"16;
%"Q_CAP"
"1","(-4975,5800)","0","pure_quanta","I19";
;
LOCATION"PC552_3"
$SEC"1"
CDS_SEC"1"
MATERIAL"X6S"
TOLERANCE"10%"
VALUE"1UF"
PART_NUMBER"CH5104KEB02"
VOLTAGE"25V"
PACK_TYPE"C0402"
CDS_LIB"pure_quanta";
"B"
$PN"2"17;
"A"
$PN"1"44;
%"Q_CAP"
"1","(-4650,5800)","0","pure_quanta","I20";
;
LOCATION"PC554_3"
$SEC"1"
CDS_SEC"1"
MATERIAL"X6S"
TOLERANCE"10%"
VALUE"10UF"
VOLTAGE"25V"
PACK_TYPE"C0805"
PART_NUMBER"CH6104KEA00"
CDS_LIB"pure_quanta";
"B"
$PN"2"17;
"A"
$PN"1"44;
%"Q_CAP"
"1","(-4325,5800)","0","pure_quanta","I21";
;
LOCATION"PC556_3"
$SEC"1"
CDS_SEC"1"
VALUE"10UF"
PART_NUMBER"CH6104KEA00"
VOLTAGE"25V"
PACK_TYPE"C0805"
TOLERANCE"10%"
MATERIAL"X6S"
CDS_LIB"pure_quanta";
"B"
$PN"2"17;
"A"
$PN"1"44;
%"Q_INDUCTOR4P_14"
"1","(-2825,4775)","0","pure_quanta","I23";
;
LOCATION"PL59"
$SEC"1"
CDS_SEC"1"
PART_TYPE"SMLF"
MATERIAL"IND"
VALUE"150NH"
PART_NUMBER"CV+15^0TZ04"
CDS_LIB"pure_quanta"
NEEDS_NO_SIZE"TRUE";
"1"
$PN"1"18;
"4"
$PN"4"52;
"3"
$PN"3"55;
"2"
$PN"2"53;
%"Q_CAP"
"1","(-3550,5125)","0","pure_quanta","I26";
;
LOCATION"PC560"
$SEC"1"
CDS_SEC"1"
MATERIAL"X7R"
TOLERANCE"10%"
VALUE"0.22UF"
PART_NUMBER"CH4223K1B00"
VOLTAGE"16V"
PACK_TYPE"0402"
CDS_LIB"pure_quanta";
"B"
$PN"2"15;
"A"
$PN"1"54;
%"UNIVERSAL_GND"
"1","(-4025,5475)","0","pure_quanta_power","I27";
;
CDS_LIB"pure_quanta_power"
HDL_POWER"GND";
"A"17;
%"Q_CAP"
"1","(-4025,5800)","0","pure_quanta","I28";
;
LOCATION"PC558_3"
$SEC"1"
CDS_SEC"1"
MATERIAL"X6S"
TOLERANCE"10%"
VALUE"10UF"
PART_NUMBER"CH6104KEA00"
VOLTAGE"25V"
PACK_TYPE"C0805"
CDS_LIB"pure_quanta";
"B"
$PN"2"17;
"A"
$PN"1"44;
%"VCC_CORE"
"1","(-4025,6100)","0","pure_quanta_power","I29";
;
HDL_POWER"SW_P12V_STBY_PVDDCR_CPU0_P0_FLT"
CDS_LIB"pure_quanta_power";
"A"44;
%"Q_CAP"
"1","(-7775,4625)","0","pure_quanta","I3";
;
LOCATION"PC544_3"
$SEC"1"
CDS_SEC"1"
MATERIAL"X7R"
TOLERANCE"10%"
VALUE"0.1UF"
PART_NUMBER"CH4104K1B00"
VOLTAGE"25V"
PACK_TYPE"0402"
CDS_LIB"pure_quanta";
"B"
$PN"2"1;
"A"
$PN"1"36;
%"Q_CAP"
"1","(-1500,4725)","0","pure_quanta","I31";
;
LOCATION"PC562_3"
$SEC"1"
CDS_SEC"1"
MATERIAL"X6S"
TOLERANCE"20%"
VALUE"22UF"
PART_NUMBER"TMP_QCH622KMEA01"
VOLTAGE"4V"
PACK_TYPE"0805"
CDS_LIB"pure_quanta";
"B"
$PN"2"56;
"A"
$PN"1"52;
%"UNIVERSAL_GND"
"1","(-1075,4375)","0","pure_quanta_power","I32";
;
CDS_LIB"pure_quanta_power"
HDL_POWER"GND";
"A"56;
%"Q_CAP"
"1","(-1075,4725)","0","pure_quanta","I33";
;
LOCATION"PC564_3"
$SEC"1"
CDS_SEC"1"
MATERIAL"X6S"
TOLERANCE"20%"
VALUE"22UF"
PART_NUMBER"TMP_QCH622KMEA01"
VOLTAGE"4V"
PACK_TYPE"0805"
CDS_LIB"pure_quanta";
"B"
$PN"2"56;
"A"
$PN"1"52;
%"VCC_CORE"
"1","(-1075,5050)","0","pure_quanta_power","I34";
;
HDL_POWER"PVDDCR_CPU0_P0"
CDS_LIB"pure_quanta_power";
"A"52;
%"UNIVERSAL_GND"
"1","(-7450,4425)","0","pure_quanta_power","I4";
;
CDS_LIB"pure_quanta_power"
HDL_POWER"GND";
"A"10;
%"VCC_CORE"
"1","(-900,1750)","0","pure_quanta_power","I74";
;
HDL_POWER"PVDDCR_CPU0_P0"
CDS_LIB"pure_quanta_power";
"A"49;
%"Q_CAP"
"1","(-900,1425)","0","pure_quanta","I75";
;
LOCATION"PC565_4"
$SEC"1"
CDS_SEC"1"
MATERIAL"X6S"
TOLERANCE"20%"
VALUE"22UF"
PART_NUMBER"TMP_QCH622KMEA01"
VOLTAGE"4V"
PACK_TYPE"0805"
CDS_LIB"pure_quanta";
"B"
$PN"2"51;
"A"
$PN"1"49;
%"UNIVERSAL_GND"
"1","(-900,925)","0","pure_quanta_power","I76";
;
CDS_LIB"pure_quanta_power"
HDL_POWER"GND";
"A"51;
%"Q_CAP"
"1","(-1400,1425)","0","pure_quanta","I77";
;
LOCATION"PC563_4"
$SEC"1"
CDS_SEC"1"
MATERIAL"X6S"
TOLERANCE"20%"
VALUE"22UF"
PART_NUMBER"TMP_QCH622KMEA01"
VOLTAGE"4V"
PACK_TYPE"0805"
CDS_LIB"pure_quanta";
"B"
$PN"2"51;
"A"
$PN"1"49;
%"Q_RES"
"1","(-7125,4600)","0","pure_quanta","I8";
;
LOCATION"PR346"
$SEC"1"
CDS_SEC"1"
WATTAGE"1/16W"
MATERIAL"EMPTY"
TOLERANCE"1%"
VALUE"8.87K"
PART_NUMBER"CS28872FB01"
PACK_TYPE"0402LF"
CDS_LIB"pure_quanta";
"B"
$PN"2"38;
"A"
$PN"1"10;
%"VCC_CORE"
"1","(-3800,2800)","0","pure_quanta_power","I81";
;
HDL_POWER"SW_P12V_STBY_PVDDCR_CPU0_P0_FLT"
CDS_LIB"pure_quanta_power";
"A"33;
%"Q_CAP"
"1","(-3800,2500)","0","pure_quanta","I82";
;
LOCATION"PC559_4"
$SEC"1"
CDS_SEC"1"
VALUE"10UF"
VOLTAGE"25V"
TOLERANCE"10%"
MATERIAL"X6S"
PART_NUMBER"CH6104KEA00"
PACK_TYPE"C0805"
CDS_LIB"pure_quanta";
"B"
$PN"2"12;
"A"
$PN"1"33;
%"UNIVERSAL_GND"
"1","(-3800,2150)","0","pure_quanta_power","I83";
;
CDS_LIB"pure_quanta_power"
HDL_POWER"GND";
"A"12;
%"Q_INDUCTOR4P_14"
"1","(-2800,1475)","0","pure_quanta","I84";
;
LOCATION"PL60"
$SEC"1"
CDS_SEC"1"
PART_TYPE"SMLF"
MATERIAL"IND"
VALUE"150NH"
PART_NUMBER"CV+15^0TZ04"
CDS_LIB"pure_quanta"
NEEDS_NO_SIZE"TRUE";
"1"
$PN"1"13;
"4"
$PN"4"49;
"3"
$PN"3"50;
"2"
$PN"2"48;
%"Q_CAP"
"1","(-3500,1825)","0","pure_quanta","I85";
;
LOCATION"PC561"
$SEC"1"
CDS_SEC"1"
MATERIAL"X7R"
TOLERANCE"10%"
VALUE"0.22UF"
PART_NUMBER"CH4223K1B00"
VOLTAGE"16V"
PACK_TYPE"0402"
CDS_LIB"pure_quanta";
"B"
$PN"2"14;
"A"
$PN"1"11;
%"Q_CAP"
"1","(-4175,2500)","0","pure_quanta","I86";
;
LOCATION"PC557_4"
$SEC"1"
CDS_SEC"1"
MATERIAL"X6S"
TOLERANCE"10%"
VALUE"10UF"
PART_NUMBER"CH6104KEA00"
VOLTAGE"25V"
PACK_TYPE"C0805"
CDS_LIB"pure_quanta";
"B"
$PN"2"12;
"A"
$PN"1"33;
%"Q_CAP"
"1","(-4500,2500)","0","pure_quanta","I87";
;
LOCATION"PC555_4"
$SEC"1"
CDS_SEC"1"
MATERIAL"X6S"
TOLERANCE"10%"
VALUE"10UF"
PART_NUMBER"CH6104KEA00"
VOLTAGE"25V"
PACK_TYPE"C0805"
CDS_LIB"pure_quanta";
"B"
$PN"2"12;
"A"
$PN"1"33;
%"Q_CAP"
"1","(-4825,2500)","0","pure_quanta","I88";
;
LOCATION"PC553_4"
$SEC"1"
CDS_SEC"1"
MATERIAL"X6S"
TOLERANCE"10%"
VALUE"1UF"
PART_NUMBER"CH5104KEB02"
VOLTAGE"25V"
PACK_TYPE"C0402"
CDS_LIB"pure_quanta";
"B"
$PN"2"12;
"A"
$PN"1"33;
%"Q_RES"
"1","(-4475,1950)","0","pure_quanta","I89";
;
LOCATION"PR349"
$SEC"1"
CDS_SEC"1"
PACK_TYPE"0402LF"
TOLERANCE"1%"
MATERIAL"CHIP"
WATTAGE"1/16W"
VALUE"4.7"
PART_NUMBER"CS-4702FB19"
CDS_LIB"pure_quanta";
"B"
$PN"2"11;
"A"
$PN"1"30;
%"Q_RES"
"1","(-3975,700)","0","pure_quanta","I90";
;
LOCATION"PR351"
$SEC"1"
CDS_SEC"1"
WATTAGE"1/16W"
MATERIAL"CHIP"
TOLERANCE"5%"
VALUE"0"
PART_NUMBER"CS00002JB38"
PACK_TYPE"0402LF"
CDS_LIB"pure_quanta";
"B"
$PN"2"49;
"A"
$PN"1"31;
%"UNIVERSAL_GND"
"1","(-5325,850)","0","pure_quanta_power","I92";
;
CDS_LIB"pure_quanta_power"
HDL_POWER"GND";
"A"27;
%"Q_RES"
"1","(-7050,1300)","0","pure_quanta","I96";
;
LOCATION"PR347"
$SEC"1"
CDS_SEC"1"
WATTAGE"1/16W"
MATERIAL"EMPTY"
TOLERANCE"1%"
VALUE"8.87K"
PART_NUMBER"CS28872FB01"
PACK_TYPE"0402LF"
CDS_LIB"pure_quanta";
"B"
$PN"2"21;
"A"
$PN"1"2;
END.
